FILE_TYPE = MACRO_DRAWING;
SET COLOR_WIRE YELLOW;
SET COLOR_PROP MONO;
SET COLOR_DOT WHITE;
SET COLOR_ARC YELLOW;
SET COLOR_BODY GREEN;
SET COLOR_NOTE MONO;
SET PROP_DISPLAY VALUE;
SET PAGE_NUMBER P123;
FORCEADD LBG_CORE_QAT_EXT_D..11
(-1625 2575);
FORCEPROP 1 LAST LOCATION U7C1
J 0
(-2175 4525);
DISPLAY 0.617021 (-2175 4525);
PAINT AQUA (-2175 4525);
FORCEPROP 1 LAST PART_NUMBER H91415-002
J 0
(-2175 625);
DISPLAY 0.617021 (-2175 625);
PAINT BLUE (-2175 625);
FORCEPROP 1 LAST MATERIAL IC
J 0
(-2175 4475);
DISPLAY 0.617021 (-2175 4475);
PAINT SKYBLUE (-2175 4475);
FORCEPROP 2 LASTPIN (-1025 825) $PN N31
J 0
(-1015 835);
DISPLAY 0.617021 (-1015 835);
PAINT ORANGE (-1015 835);
FORCEPROP 2 LASTPIN (-1025 875) $PN N27
J 0
(-1015 885);
DISPLAY 0.617021 (-1015 885);
PAINT ORANGE (-1015 885);
FORCEPROP 2 LASTPIN (-1025 925) $PN N24
J 0
(-1015 935);
DISPLAY 0.617021 (-1015 935);
PAINT ORANGE (-1015 935);
FORCEPROP 2 LASTPIN (-1025 975) $PN N20
J 0
(-1015 985);
DISPLAY 0.617021 (-1015 985);
PAINT ORANGE (-1015 985);
FORCEPROP 2 LASTPIN (-1025 1025) $PN N17
J 0
(-1015 1035);
DISPLAY 0.617021 (-1015 1035);
PAINT ORANGE (-1015 1035);
FORCEPROP 2 LASTPIN (-1025 1075) $PN N13
J 0
(-1015 1085);
DISPLAY 0.617021 (-1015 1085);
PAINT ORANGE (-1015 1085);
FORCEPROP 2 LASTPIN (-1025 1125) $PN M48
J 0
(-1015 1135);
DISPLAY 0.617021 (-1015 1135);
PAINT ORANGE (-1015 1135);
FORCEPROP 2 LASTPIN (-1025 1175) $PN M44
J 0
(-1015 1185);
DISPLAY 0.617021 (-1015 1185);
PAINT ORANGE (-1015 1185);
FORCEPROP 2 LASTPIN (-1025 1225) $PN N50
J 0
(-1015 1235);
DISPLAY 0.617021 (-1015 1235);
PAINT ORANGE (-1015 1235);
FORCEPROP 2 LASTPIN (-1025 1275) $PN N42
J 0
(-1015 1285);
DISPLAY 0.617021 (-1015 1285);
PAINT ORANGE (-1015 1285);
FORCEPROP 2 LASTPIN (-1025 1325) $PN M40
J 0
(-1015 1335);
DISPLAY 0.617021 (-1015 1335);
PAINT ORANGE (-1015 1335);
FORCEPROP 2 LASTPIN (-1025 1375) $PN M4
J 0
(-1015 1385);
DISPLAY 0.617021 (-1015 1385);
PAINT ORANGE (-1015 1385);
FORCEPROP 2 LASTPIN (-1025 1425) $PN M37
J 0
(-1015 1435);
DISPLAY 0.617021 (-1015 1435);
PAINT ORANGE (-1015 1435);
FORCEPROP 2 LASTPIN (-1025 1475) $PN M33
J 0
(-1015 1485);
DISPLAY 0.617021 (-1015 1485);
PAINT ORANGE (-1015 1485);
FORCEPROP 2 LASTPIN (-1025 1525) $PN M29
J 0
(-1015 1535);
DISPLAY 0.617021 (-1015 1535);
PAINT ORANGE (-1015 1535);
FORCEPROP 2 LASTPIN (-1025 1575) $PN M26
J 0
(-1015 1585);
DISPLAY 0.617021 (-1015 1585);
PAINT ORANGE (-1015 1585);
FORCEPROP 2 LASTPIN (-1025 1625) $PN M22
J 0
(-1015 1635);
DISPLAY 0.617021 (-1015 1635);
PAINT ORANGE (-1015 1635);
FORCEPROP 2 LASTPIN (-1025 1675) $PN M2
J 0
(-1015 1685);
DISPLAY 0.617021 (-1015 1685);
PAINT ORANGE (-1015 1685);
FORCEPROP 2 LASTPIN (-1025 1725) $PN L68
J 0
(-1015 1735);
DISPLAY 0.617021 (-1015 1735);
PAINT ORANGE (-1015 1735);
FORCEPROP 2 LASTPIN (-1025 1775) $PN L5
J 0
(-1015 1785);
DISPLAY 0.617021 (-1015 1785);
PAINT ORANGE (-1015 1785);
FORCEPROP 2 LASTPIN (-1025 1825) $PN K71
J 0
(-1015 1835);
DISPLAY 0.617021 (-1015 1835);
PAINT ORANGE (-1015 1835);
FORCEPROP 2 LASTPIN (-1025 1875) $PN K69
J 0
(-1015 1885);
DISPLAY 0.617021 (-1015 1885);
PAINT ORANGE (-1015 1885);
FORCEPROP 2 LASTPIN (-1025 1925) $PN K54
J 0
(-1015 1935);
DISPLAY 0.617021 (-1015 1935);
PAINT ORANGE (-1015 1935);
FORCEPROP 2 LASTPIN (-1025 1975) $PN J70
J 0
(-1015 1985);
DISPLAY 0.617021 (-1015 1985);
PAINT ORANGE (-1015 1985);
FORCEPROP 2 LASTPIN (-1025 2025) $PN J68
J 0
(-1015 2035);
DISPLAY 0.617021 (-1015 2035);
PAINT ORANGE (-1015 2035);
FORCEPROP 2 LASTPIN (-1025 2075) $PN J59
J 0
(-1015 2085);
DISPLAY 0.617021 (-1015 2085);
PAINT ORANGE (-1015 2085);
FORCEPROP 2 LASTPIN (-1025 2125) $PN J44
J 0
(-1015 2135);
DISPLAY 0.617021 (-1015 2135);
PAINT ORANGE (-1015 2135);
FORCEPROP 2 LASTPIN (-1025 2175) $PN J37
J 0
(-1015 2185);
DISPLAY 0.617021 (-1015 2185);
PAINT ORANGE (-1015 2185);
FORCEPROP 2 LASTPIN (-1025 2225) $PN J22
J 0
(-1015 2235);
DISPLAY 0.617021 (-1015 2235);
PAINT ORANGE (-1015 2235);
FORCEPROP 2 LASTPIN (-1025 2275) $PN J15
J 0
(-1015 2285);
DISPLAY 0.617021 (-1015 2285);
PAINT ORANGE (-1015 2285);
FORCEPROP 2 LASTPIN (-1025 2325) $PN J11
J 0
(-1015 2335);
DISPLAY 0.617021 (-1015 2335);
PAINT ORANGE (-1015 2335);
FORCEPROP 2 LASTPIN (-1025 2375) $PN H65
J 0
(-1015 2385);
DISPLAY 0.617021 (-1015 2385);
PAINT ORANGE (-1015 2385);
FORCEPROP 2 LASTPIN (-1025 2425) $PN J7
J 0
(-1015 2435);
DISPLAY 0.617021 (-1015 2435);
PAINT ORANGE (-1015 2435);
FORCEPROP 2 LASTPIN (-1025 2475) $PN J5
J 0
(-1015 2485);
DISPLAY 0.617021 (-1015 2485);
PAINT ORANGE (-1015 2485);
FORCEPROP 2 LASTPIN (-1025 2525) $PN J29
J 0
(-1015 2535);
DISPLAY 0.617021 (-1015 2535);
PAINT ORANGE (-1015 2535);
FORCEPROP 2 LASTPIN (-1025 2575) $PN H58
J 0
(-1015 2585);
DISPLAY 0.617021 (-1015 2585);
PAINT ORANGE (-1015 2585);
FORCEPROP 2 LASTPIN (-1025 2625) $PN G66
J 0
(-1015 2635);
DISPLAY 0.617021 (-1015 2635);
PAINT ORANGE (-1015 2635);
FORCEPROP 2 LASTPIN (-1025 2675) $PN G63
J 0
(-1015 2685);
DISPLAY 0.617021 (-1015 2685);
PAINT ORANGE (-1015 2685);
FORCEPROP 2 LASTPIN (-1025 2725) $PN G6
J 0
(-1015 2735);
DISPLAY 0.617021 (-1015 2735);
PAINT ORANGE (-1015 2735);
FORCEPROP 2 LASTPIN (-1025 2775) $PN G48
J 0
(-1015 2785);
DISPLAY 0.617021 (-1015 2785);
PAINT ORANGE (-1015 2785);
FORCEPROP 2 LASTPIN (-1025 2825) $PN G37
J 0
(-1015 2835);
DISPLAY 0.617021 (-1015 2835);
PAINT ORANGE (-1015 2835);
FORCEPROP 2 LASTPIN (-1025 2875) $PN G29
J 0
(-1015 2885);
DISPLAY 0.617021 (-1015 2885);
PAINT ORANGE (-1015 2885);
FORCEPROP 2 LASTPIN (-1025 2925) $PN G22
J 0
(-1015 2935);
DISPLAY 0.617021 (-1015 2935);
PAINT ORANGE (-1015 2935);
FORCEPROP 2 LASTPIN (-1025 2975) $PN E9
J 0
(-1015 2985);
DISPLAY 0.617021 (-1015 2985);
PAINT ORANGE (-1015 2985);
FORCEPROP 2 LASTPIN (-1025 3025) $PN G59
J 0
(-1015 3035);
DISPLAY 0.617021 (-1015 3035);
PAINT ORANGE (-1015 3035);
FORCEPROP 2 LASTPIN (-1025 3075) $PN E63
J 0
(-1015 3085);
DISPLAY 0.617021 (-1015 3085);
PAINT ORANGE (-1015 3085);
FORCEPROP 2 LASTPIN (-1025 3125) $PN E61
J 0
(-1015 3135);
DISPLAY 0.617021 (-1015 3135);
PAINT ORANGE (-1015 3135);
FORCEPROP 2 LASTPIN (-1025 3175) $PN E6
J 0
(-1015 3185);
DISPLAY 0.617021 (-1015 3185);
PAINT ORANGE (-1015 3185);
FORCEPROP 2 LASTPIN (-1025 3225) $PN E57
J 0
(-1015 3235);
DISPLAY 0.617021 (-1015 3235);
PAINT ORANGE (-1015 3235);
FORCEPROP 2 LASTPIN (-1025 3275) $PN E54
J 0
(-1015 3285);
DISPLAY 0.617021 (-1015 3285);
PAINT ORANGE (-1015 3285);
FORCEPROP 2 LASTPIN (-1025 3325) $PN E52
J 0
(-1015 3335);
DISPLAY 0.617021 (-1015 3335);
PAINT ORANGE (-1015 3335);
FORCEPROP 2 LASTPIN (-1025 3375) $PN E50
J 0
(-1015 3385);
DISPLAY 0.617021 (-1015 3385);
PAINT ORANGE (-1015 3385);
FORCEPROP 2 LASTPIN (-1025 3425) $PN E48
J 0
(-1015 3435);
DISPLAY 0.617021 (-1015 3435);
PAINT ORANGE (-1015 3435);
FORCEPROP 2 LASTPIN (-1025 3475) $PN E45
J 0
(-1015 3485);
DISPLAY 0.617021 (-1015 3485);
PAINT ORANGE (-1015 3485);
FORCEPROP 2 LASTPIN (-1025 3525) $PN E43
J 0
(-1015 3535);
DISPLAY 0.617021 (-1015 3535);
PAINT ORANGE (-1015 3535);
FORCEPROP 2 LASTPIN (-1025 3575) $PN E41
J 0
(-1015 3585);
DISPLAY 0.617021 (-1015 3585);
PAINT ORANGE (-1015 3585);
FORCEPROP 2 LASTPIN (-1025 3625) $PN E39
J 0
(-1015 3635);
DISPLAY 0.617021 (-1015 3635);
PAINT ORANGE (-1015 3635);
FORCEPROP 2 LASTPIN (-1025 3675) $PN E37
J 0
(-1015 3685);
DISPLAY 0.617021 (-1015 3685);
PAINT ORANGE (-1015 3685);
FORCEPROP 2 LASTPIN (-1025 3725) $PN E34
J 0
(-1015 3735);
DISPLAY 0.617021 (-1015 3735);
PAINT ORANGE (-1015 3735);
FORCEPROP 2 LASTPIN (-1025 3775) $PN E32
J 0
(-1015 3785);
DISPLAY 0.617021 (-1015 3785);
PAINT ORANGE (-1015 3785);
FORCEPROP 2 LASTPIN (-1025 3825) $PN E30
J 0
(-1015 3835);
DISPLAY 0.617021 (-1015 3835);
PAINT ORANGE (-1015 3835);
FORCEPROP 2 LASTPIN (-1025 3875) $PN E28
J 0
(-1015 3885);
DISPLAY 0.617021 (-1015 3885);
PAINT ORANGE (-1015 3885);
FORCEPROP 2 LASTPIN (-1025 3925) $PN E26
J 0
(-1015 3935);
DISPLAY 0.617021 (-1015 3935);
PAINT ORANGE (-1015 3935);
FORCEPROP 2 LASTPIN (-1025 3975) $PN E24
J 0
(-1015 3985);
DISPLAY 0.617021 (-1015 3985);
PAINT ORANGE (-1015 3985);
FORCEPROP 2 LASTPIN (-1025 4025) $PN E22
J 0
(-1015 4035);
DISPLAY 0.617021 (-1015 4035);
PAINT ORANGE (-1015 4035);
FORCEPROP 2 LASTPIN (-1025 4075) $PN E20
J 0
(-1015 4085);
DISPLAY 0.617021 (-1015 4085);
PAINT ORANGE (-1015 4085);
FORCEPROP 2 LASTPIN (-1025 4125) $PN E15
J 0
(-1015 4135);
DISPLAY 0.617021 (-1015 4135);
PAINT ORANGE (-1015 4135);
FORCEPROP 2 LASTPIN (-1025 4175) $PN E13
J 0
(-1015 4185);
DISPLAY 0.617021 (-1015 4185);
PAINT ORANGE (-1015 4185);
FORCEPROP 2 LASTPIN (-1025 4225) $PN E11
J 0
(-1015 4235);
DISPLAY 0.617021 (-1015 4235);
PAINT ORANGE (-1015 4235);
FORCEPROP 2 LASTPIN (-1025 4275) $PN D47
J 0
(-1015 4285);
DISPLAY 0.617021 (-1015 4285);
PAINT ORANGE (-1015 4285);
FORCEPROP 2 LASTPIN (-2225 825) $PN E65
J 2
(-2235 835);
DISPLAY 0.617021 (-2235 835);
PAINT ORANGE (-2235 835);
FORCEPROP 2 LASTPIN (-2225 875) $PN E59
J 2
(-2235 885);
DISPLAY 0.617021 (-2235 885);
PAINT ORANGE (-2235 885);
FORCEPROP 2 LASTPIN (-2225 925) $PN D27
J 2
(-2235 935);
DISPLAY 0.617021 (-2235 935);
PAINT ORANGE (-2235 935);
FORCEPROP 2 LASTPIN (-2225 975) $PN D25
J 2
(-2235 985);
DISPLAY 0.617021 (-2235 985);
PAINT ORANGE (-2235 985);
FORCEPROP 2 LASTPIN (-2225 1025) $PN D19
J 2
(-2235 1035);
DISPLAY 0.617021 (-2235 1035);
PAINT ORANGE (-2235 1035);
FORCEPROP 2 LASTPIN (-2225 1075) $PN D16
J 2
(-2235 1085);
DISPLAY 0.617021 (-2235 1085);
PAINT ORANGE (-2235 1085);
FORCEPROP 2 LASTPIN (-2225 1125) $PN D12
J 2
(-2235 1135);
DISPLAY 0.617021 (-2235 1135);
PAINT ORANGE (-2235 1135);
FORCEPROP 2 LASTPIN (-2225 1175) $PN C65
J 2
(-2235 1185);
DISPLAY 0.617021 (-2235 1185);
PAINT ORANGE (-2235 1185);
FORCEPROP 2 LASTPIN (-2225 1225) $PN C41
J 2
(-2235 1235);
DISPLAY 0.617021 (-2235 1235);
PAINT ORANGE (-2235 1235);
FORCEPROP 2 LASTPIN (-2225 1275) $PN C37
J 2
(-2235 1285);
DISPLAY 0.617021 (-2235 1285);
PAINT ORANGE (-2235 1285);
FORCEPROP 2 LASTPIN (-2225 1325) $PN C34
J 2
(-2235 1335);
DISPLAY 0.617021 (-2235 1335);
PAINT ORANGE (-2235 1335);
FORCEPROP 2 LASTPIN (-2225 1375) $PN C30
J 2
(-2235 1385);
DISPLAY 0.617021 (-2235 1385);
PAINT ORANGE (-2235 1385);
FORCEPROP 2 LASTPIN (-2225 1425) $PN C22
J 2
(-2235 1435);
DISPLAY 0.617021 (-2235 1435);
PAINT ORANGE (-2235 1435);
FORCEPROP 2 LASTPIN (-2225 1475) $PN B47
J 2
(-2235 1485);
DISPLAY 0.617021 (-2235 1485);
PAINT ORANGE (-2235 1485);
FORCEPROP 2 LASTPIN (-2225 1525) $PN B27
J 2
(-2235 1535);
DISPLAY 0.617021 (-2235 1535);
PAINT ORANGE (-2235 1535);
FORCEPROP 2 LASTPIN (-2225 1575) $PN B25
J 2
(-2235 1585);
DISPLAY 0.617021 (-2235 1585);
PAINT ORANGE (-2235 1585);
FORCEPROP 2 LASTPIN (-2225 1625) $PN B19
J 2
(-2235 1635);
DISPLAY 0.617021 (-2235 1635);
PAINT ORANGE (-2235 1635);
FORCEPROP 2 LASTPIN (-2225 1675) $PN B12
J 2
(-2235 1685);
DISPLAY 0.617021 (-2235 1685);
PAINT ORANGE (-2235 1685);
FORCEPROP 2 LASTPIN (-2225 1775) $PN A37
J 2
(-2235 1785);
DISPLAY 0.617021 (-2235 1785);
PAINT ORANGE (-2235 1785);
FORCEPROP 2 LASTPIN (-2225 1825) $PN A34
J 2
(-2235 1835);
DISPLAY 0.617021 (-2235 1835);
PAINT ORANGE (-2235 1835);
FORCEPROP 2 LASTPIN (-2225 1875) $PN A30
J 2
(-2235 1885);
DISPLAY 0.617021 (-2235 1885);
PAINT ORANGE (-2235 1885);
FORCEPROP 2 LASTPIN (-2225 1925) $PN A22
J 2
(-2235 1935);
DISPLAY 0.617021 (-2235 1935);
PAINT ORANGE (-2235 1935);
FORCEPROP 2 LASTPIN (-2225 1975) $PN A18
J 2
(-2235 1985);
DISPLAY 0.617021 (-2235 1985);
PAINT ORANGE (-2235 1985);
FORCEPROP 2 LASTPIN (-2225 2025) $PN Y70
J 2
(-2235 2035);
DISPLAY 0.617021 (-2235 2035);
PAINT ORANGE (-2235 2035);
FORCEPROP 2 LASTPIN (-2225 2075) $PN Y72
J 2
(-2235 2085);
DISPLAY 0.617021 (-2235 2085);
PAINT ORANGE (-2235 2085);
FORCEPROP 2 LASTPIN (-2225 2125) $PN AT37
J 2
(-2235 2135);
DISPLAY 0.617021 (-2235 2135);
PAINT ORANGE (-2235 2135);
FORCEPROP 2 LASTPIN (-2225 2175) $PN BB48
J 2
(-2235 2185);
DISPLAY 0.617021 (-2235 2185);
PAINT ORANGE (-2235 2185);
FORCEPROP 2 LASTPIN (-2225 2225) $PN CA70
J 2
(-2235 2235);
DISPLAY 0.617021 (-2235 2235);
PAINT ORANGE (-2235 2235);
FORCEPROP 2 LASTPIN (-2225 2275) $PN BW72
J 2
(-2235 2285);
DISPLAY 0.617021 (-2235 2285);
PAINT ORANGE (-2235 2285);
FORCEPROP 2 LASTPIN (-2225 2325) $PN BW70
J 2
(-2235 2335);
DISPLAY 0.617021 (-2235 2335);
PAINT ORANGE (-2235 2335);
FORCEPROP 2 LASTPIN (-2225 2375) $PN BU72
J 2
(-2235 2385);
DISPLAY 0.617021 (-2235 2385);
PAINT ORANGE (-2235 2385);
FORCEPROP 2 LASTPIN (-2225 2425) $PN BR72
J 2
(-2235 2435);
DISPLAY 0.617021 (-2235 2435);
PAINT ORANGE (-2235 2435);
FORCEPROP 2 LASTPIN (-2225 2475) $PN G72
J 2
(-2235 2485);
DISPLAY 0.617021 (-2235 2485);
PAINT ORANGE (-2235 2485);
FORCEPROP 2 LASTPIN (-2225 2525) $PN G1
J 2
(-2235 2535);
DISPLAY 0.617021 (-2235 2535);
PAINT ORANGE (-2235 2535);
FORCEPROP 2 LASTPIN (-2225 2575) $PN E72
J 2
(-2235 2585);
DISPLAY 0.617021 (-2235 2585);
PAINT ORANGE (-2235 2585);
FORCEPROP 2 LASTPIN (-2225 2625) $PN E1
J 2
(-2235 2635);
DISPLAY 0.617021 (-2235 2635);
PAINT ORANGE (-2235 2635);
FORCEPROP 2 LASTPIN (-2225 2675) $PN C72
J 2
(-2235 2685);
DISPLAY 0.617021 (-2235 2685);
PAINT ORANGE (-2235 2685);
FORCEPROP 2 LASTPIN (-2225 2725) $PN C3
J 2
(-2235 2735);
DISPLAY 0.617021 (-2235 2735);
PAINT ORANGE (-2235 2735);
FORCEPROP 2 LASTPIN (-2225 2775) $PN BR1
J 2
(-2235 2785);
DISPLAY 0.617021 (-2235 2785);
PAINT ORANGE (-2235 2785);
FORCEPROP 2 LASTPIN (-2225 2825) $PN BU1
J 2
(-2235 2835);
DISPLAY 0.617021 (-2235 2835);
PAINT ORANGE (-2235 2835);
FORCEPROP 2 LASTPIN (-2225 2875) $PN BW1
J 2
(-2235 2885);
DISPLAY 0.617021 (-2235 2885);
PAINT ORANGE (-2235 2885);
FORCEPROP 2 LASTPIN (-2225 2925) $PN CA3
J 2
(-2235 2935);
DISPLAY 0.617021 (-2235 2935);
PAINT ORANGE (-2235 2935);
FORCEPROP 2 LASTPIN (-2225 2975) $PN A70
J 2
(-2235 2985);
DISPLAY 0.617021 (-2235 2985);
PAINT ORANGE (-2235 2985);
FORCEPROP 2 LASTPIN (-2225 3025) $PN CA5
J 2
(-2235 3035);
DISPLAY 0.617021 (-2235 3035);
PAINT ORANGE (-2235 3035);
FORCEPROP 2 LASTPIN (-2225 3075) $PN CA7
J 2
(-2235 3085);
DISPLAY 0.617021 (-2235 3085);
PAINT ORANGE (-2235 3085);
FORCEPROP 2 LASTPIN (-2225 3125) $PN CA9
J 2
(-2235 3135);
DISPLAY 0.617021 (-2235 3135);
PAINT ORANGE (-2235 3135);
FORCEPROP 2 LASTPIN (-2225 3175) $PN CA65
J 2
(-2235 3185);
DISPLAY 0.617021 (-2235 3185);
PAINT ORANGE (-2235 3185);
FORCEPROP 2 LASTPIN (-2225 3225) $PN CA66
J 2
(-2235 3235);
DISPLAY 0.617021 (-2235 3235);
PAINT ORANGE (-2235 3235);
FORCEPROP 2 LASTPIN (-2225 3275) $PN CA68
J 2
(-2235 3285);
DISPLAY 0.617021 (-2235 3285);
PAINT ORANGE (-2235 3285);
FORCEPROP 2 LASTPIN (-2225 3325) $PN BN72
J 2
(-2235 3335);
DISPLAY 0.617021 (-2235 3335);
PAINT ORANGE (-2235 3335);
FORCEPROP 2 LASTPIN (-2225 3375) $PN BN1
J 2
(-2235 3385);
DISPLAY 0.617021 (-2235 3385);
PAINT ORANGE (-2235 3385);
FORCEPROP 2 LASTPIN (-2225 3425) $PN J72
J 2
(-2235 3435);
DISPLAY 0.617021 (-2235 3435);
PAINT ORANGE (-2235 3435);
FORCEPROP 2 LASTPIN (-2225 3475) $PN J1
J 2
(-2235 3485);
DISPLAY 0.617021 (-2235 3485);
PAINT ORANGE (-2235 3485);
FORCEPROP 2 LASTPIN (-2225 3525) $PN A68
J 2
(-2235 3535);
DISPLAY 0.617021 (-2235 3535);
PAINT ORANGE (-2235 3535);
FORCEPROP 2 LASTPIN (-2225 3575) $PN A66
J 2
(-2235 3585);
DISPLAY 0.617021 (-2235 3585);
PAINT ORANGE (-2235 3585);
FORCEPROP 2 LASTPIN (-2225 3625) $PN A65
J 2
(-2235 3635);
DISPLAY 0.617021 (-2235 3635);
PAINT ORANGE (-2235 3635);
FORCEPROP 2 LASTPIN (-2225 3675) $PN A9
J 2
(-2235 3685);
DISPLAY 0.617021 (-2235 3685);
PAINT ORANGE (-2235 3685);
FORCEPROP 2 LASTPIN (-2225 3725) $PN A7
J 2
(-2235 3735);
DISPLAY 0.617021 (-2235 3735);
PAINT ORANGE (-2235 3735);
FORCEPROP 2 LASTPIN (-2225 3775) $PN A5
J 2
(-2235 3785);
DISPLAY 0.617021 (-2235 3785);
PAINT ORANGE (-2235 3785);
FORCEPROP 2 LASTPIN (-2225 3825) $PN E3
J 2
(-2235 3835);
DISPLAY 0.617021 (-2235 3835);
PAINT ORANGE (-2235 3835);
FORCEPROP 2 LASTPIN (-2225 3875) $PN F3
J 2
(-2235 3885);
DISPLAY 0.617021 (-2235 3885);
PAINT ORANGE (-2235 3885);
FORCEPROP 2 LASTPIN (-2225 3925) $PN BR3
J 2
(-2235 3935);
DISPLAY 0.617021 (-2235 3935);
PAINT ORANGE (-2235 3935);
FORCEPROP 2 LASTPIN (-2225 3975) $PN BU3
J 2
(-2235 3985);
DISPLAY 0.617021 (-2235 3985);
PAINT ORANGE (-2235 3985);
FORCEPROP 2 LASTPIN (-2225 4025) $PN E70
J 2
(-2235 4035);
DISPLAY 0.617021 (-2235 4035);
PAINT ORANGE (-2235 4035);
FORCEPROP 2 LASTPIN (-2225 4075) $PN F70
J 2
(-2235 4085);
DISPLAY 0.617021 (-2235 4085);
PAINT ORANGE (-2235 4085);
FORCEPROP 2 LASTPIN (-2225 4125) $PN BR70
J 2
(-2235 4135);
DISPLAY 0.617021 (-2235 4135);
PAINT ORANGE (-2235 4135);
FORCEPROP 2 LASTPIN (-2225 4175) $PN BU70
J 2
(-2235 4185);
DISPLAY 0.617021 (-2235 4185);
PAINT ORANGE (-2235 4185);
FORCEPROP 2 LASTPIN (-2225 4225) $PN BT69
J 2
(-2235 4235);
DISPLAY 0.617021 (-2235 4235);
PAINT ORANGE (-2235 4235);
FORCEPROP 2 LASTPIN (-2225 4275) $PN BP69
J 2
(-2235 4285);
DISPLAY 0.617021 (-2235 4285);
PAINT ORANGE (-2235 4285);
FORCEPROP 2 LASTPIN (-2225 1725) $PN A41
J 2
(-2235 1735);
DISPLAY 0.617021 (-2235 1735);
PAINT ORANGE (-2235 1735);
FORCEPROP 1 LAST PACK_TYPE BGA1
J 0
(-2175 4575);
PAINT SKYBLUE (-2175 4575);
DISPLAY INVISIBLE (-2175 4575);
FORCEPROP 2 LAST SEC_TYPE BGA1
J 0
(-2175 4575);
DISPLAY 1.021277 (-2175 4575);
PAINT ORANGE (-2175 4575);
DISPLAY INVISIBLE (-2175 4575);
FORCEPROP 2 LAST SEC 11
J 0
(-2175 4575);
DISPLAY 0.680851 (-2175 4575);
PAINT MONO (-2175 4575);
DISPLAY INVISIBLE (-2175 4575);
FORCEPROP 2 LAST CDS_LIB mstr_u_proc
J 0
(-1625 2575);
PAINT ORANGE (-1625 2575);
DISPLAY INVISIBLE (-1625 2575);
FORCEPROP 0 LAST BOM_COST SB
J 0
(-2175 4525);
DISPLAY 1.361702 (-2175 4525);
PAINT ORANGE (-2175 4525);
DISPLAY INVISIBLE (-2175 4525);
FORCEPROP 2 LAST CDS_LOCATION U7C1
J 0
(-2175 4525);
DISPLAY 0.617021 (-2175 4525);
PAINT AQUA (-2175 4525);
DISPLAY INVISIBLE (-2175 4525);
FORCEPROP 1 LAST PATH I13
J 0
(-1625 4475);
PAINT GREEN (-1625 4475);
DISPLAY INVISIBLE (-1625 4475);
FORCEPROP 0 LAST ROOM SB
J 0
(-2175 4425);
DISPLAY 1.361702 (-2175 4425);
PAINT ORANGE (-2175 4425);
DISPLAY INVISIBLE (-2175 4425);
FORCEADD GND..1
(-375 650);
FORCEPROP 3 LASTPIN (-375 700) SIG_NAME GND\g
J 0
(-365 710);
DISPLAY 0.659574 (-365 710);
PAINT MONO (-365 710);
DISPLAY INVISIBLE (-365 710);
FORCEPROP 1 LAST VOLTAGE 0.0V
J 0
(-420 607);
DISPLAY 0.340426 (-420 607);
PAINT SKYBLUE (-420 607);
DISPLAY INVISIBLE (-420 607);
FORCEPROP 2 LAST CDS_LIB mstr_symbols
J 0
(-375 650);
PAINT ORANGE (-375 650);
DISPLAY INVISIBLE (-375 650);
FORCEPROP 1 LAST SIZE 1B
J 0
(-300 600);
DISPLAY 0.872340 (-300 600);
PAINT AQUA (-300 600);
DISPLAY INVISIBLE (-300 600);
FORCEPROP 1 LAST BODY_TYPE PLUMBING
J 0
(-420 607);
DISPLAY 0.340426 (-420 607);
PAINT GREEN (-420 607);
DISPLAY INVISIBLE (-420 607);
FORCEPROP 1 LAST PATH I14
J 0
(-300 650);
DISPLAY 0.872340 (-300 650);
PAINT AQUA (-300 650);
DISPLAY INVISIBLE (-300 650);
FORCEPROP 1 LAST HDL_POWER GND
J 0
(-375 800);
DISPLAY 0.872340 (-375 800);
PAINT GREEN (-375 800);
DISPLAY INVISIBLE (-375 800);
FORCEADD GND..1
(-2800 650);
FORCEPROP 3 LASTPIN (-2800 700) SIG_NAME GND\g
J 0
(-2790 710);
DISPLAY 0.659574 (-2790 710);
PAINT MONO (-2790 710);
DISPLAY INVISIBLE (-2790 710);
FORCEPROP 1 LAST VOLTAGE 0.0V
J 0
(-2845 607);
DISPLAY 0.340426 (-2845 607);
PAINT SKYBLUE (-2845 607);
DISPLAY INVISIBLE (-2845 607);
FORCEPROP 1 LAST SIZE 1B
J 0
(-2725 600);
DISPLAY 0.872340 (-2725 600);
PAINT AQUA (-2725 600);
DISPLAY INVISIBLE (-2725 600);
FORCEPROP 2 LAST CDS_LIB mstr_symbols
J 0
(-2800 650);
PAINT ORANGE (-2800 650);
DISPLAY INVISIBLE (-2800 650);
FORCEPROP 1 LAST BODY_TYPE PLUMBING
J 0
(-2845 607);
DISPLAY 0.340426 (-2845 607);
PAINT GREEN (-2845 607);
DISPLAY INVISIBLE (-2845 607);
FORCEPROP 1 LAST PATH I15
J 0
(-2725 650);
DISPLAY 0.872340 (-2725 650);
PAINT AQUA (-2725 650);
DISPLAY INVISIBLE (-2725 650);
FORCEPROP 1 LAST HDL_POWER GND
J 0
(-2800 800);
DISPLAY 0.872340 (-2800 800);
PAINT GREEN (-2800 800);
DISPLAY INVISIBLE (-2800 800);
FORCEADD PVNN_PCH_STBY..1
(-6900 4400);
FORCEPROP 3 LASTPIN (-6900 4350) SIG_NAME PVNN_PCH_STBY\g
J 0
(-6890 4360);
DISPLAY 0.659574 (-6890 4360);
PAINT MONO (-6890 4360);
DISPLAY INVISIBLE (-6890 4360);
FORCEPROP 1 LAST VOLTAGE 1.0V
J 0
(-6945 4357);
DISPLAY 0.340426 (-6945 4357);
PAINT SKYBLUE (-6945 4357);
DISPLAY INVISIBLE (-6945 4357);
FORCEPROP 2 LAST CDS_LIB mstr_symbols
J 0
(-6900 4400);
PAINT ORANGE (-6900 4400);
DISPLAY INVISIBLE (-6900 4400);
FORCEPROP 1 LAST BODY_TYPE PLUMBING
J 0
(-6945 4357);
DISPLAY 0.340426 (-6945 4357);
PAINT GREEN (-6945 4357);
DISPLAY INVISIBLE (-6945 4357);
FORCEPROP 1 LAST PATH I20
J 0
(-6850 4425);
DISPLAY 0.872340 (-6850 4425);
PAINT AQUA (-6850 4425);
DISPLAY INVISIBLE (-6850 4425);
FORCEPROP 1 LAST HDL_POWER PVNN_PCH_STBY
J 1
(-6900 4450);
DISPLAY 0.872340 (-6900 4450);
PAINT GREEN (-6900 4450);
DISPLAY INVISIBLE (-6900 4450);
FORCEADD LBG_CORE_QAT_EXT_D..10
(-5375 2600);
FORCEPROP 1 LAST LOCATION U7C1
J 0
(-6100 4425);
DISPLAY 0.617021 (-6100 4425);
PAINT AQUA (-6100 4425);
FORCEPROP 1 LAST PART_NUMBER H91415-002
J 0
(-6425 900);
DISPLAY 0.617021 (-6425 900);
PAINT BLUE (-6425 900);
FORCEPROP 1 LAST MATERIAL IC
J 0
(-6425 4350);
DISPLAY 0.617021 (-6425 4350);
PAINT SKYBLUE (-6425 4350);
FORCEPROP 2 LASTPIN (-6475 2650) $PN AE27
J 2
(-6485 2660);
DISPLAY 0.617021 (-6485 2660);
PAINT ORANGE (-6485 2660);
FORCEPROP 2 LASTPIN (-4275 4150) $PN AK32
J 0
(-4265 4160);
DISPLAY 0.617021 (-4265 4160);
PAINT ORANGE (-4265 4160);
FORCEPROP 2 LASTPIN (-6475 4150) $PN U31
J 2
(-6485 4160);
DISPLAY 0.617021 (-6485 4160);
PAINT ORANGE (-6485 4160);
FORCEPROP 2 LASTPIN (-6475 4100) $PN U35
J 2
(-6485 4110);
DISPLAY 0.617021 (-6485 4110);
PAINT ORANGE (-6485 4110);
FORCEPROP 2 LASTPIN (-6475 4050) $PN U38
J 2
(-6485 4060);
DISPLAY 0.617021 (-6485 4060);
PAINT ORANGE (-6485 4060);
FORCEPROP 2 LASTPIN (-6475 3950) $PN V33
J 2
(-6485 3960);
DISPLAY 0.617021 (-6485 3960);
PAINT ORANGE (-6485 3960);
FORCEPROP 2 LASTPIN (-6475 3900) $PN V40
J 2
(-6485 3910);
DISPLAY 0.617021 (-6485 3910);
PAINT ORANGE (-6485 3910);
FORCEPROP 2 LASTPIN (-6475 3850) $PN Y29
J 2
(-6485 3860);
DISPLAY 0.617021 (-6485 3860);
PAINT ORANGE (-6485 3860);
FORCEPROP 2 LASTPIN (-6475 3800) $PN Y30
J 2
(-6485 3810);
DISPLAY 0.617021 (-6485 3810);
PAINT ORANGE (-6485 3810);
FORCEPROP 2 LASTPIN (-6475 3750) $PN Y32
J 2
(-6485 3760);
DISPLAY 0.617021 (-6485 3760);
PAINT ORANGE (-6485 3760);
FORCEPROP 2 LASTPIN (-6475 3700) $PN Y34
J 2
(-6485 3710);
DISPLAY 0.617021 (-6485 3710);
PAINT ORANGE (-6485 3710);
FORCEPROP 2 LASTPIN (-6475 3650) $PN Y36
J 2
(-6485 3660);
DISPLAY 0.617021 (-6485 3660);
PAINT ORANGE (-6485 3660);
FORCEPROP 2 LASTPIN (-6475 3600) $PN Y37
J 2
(-6485 3610);
DISPLAY 0.617021 (-6485 3610);
PAINT ORANGE (-6485 3610);
FORCEPROP 2 LASTPIN (-6475 3550) $PN Y39
J 2
(-6485 3560);
DISPLAY 0.617021 (-6485 3560);
PAINT ORANGE (-6485 3560);
FORCEPROP 2 LASTPIN (-6475 3500) $PN Y41
J 2
(-6485 3510);
DISPLAY 0.617021 (-6485 3510);
PAINT ORANGE (-6485 3510);
FORCEPROP 2 LASTPIN (-6475 3450) $PN AA29
J 2
(-6485 3460);
DISPLAY 0.617021 (-6485 3460);
PAINT ORANGE (-6485 3460);
FORCEPROP 2 LASTPIN (-6475 3400) $PN AA30
J 2
(-6485 3410);
DISPLAY 0.617021 (-6485 3410);
PAINT ORANGE (-6485 3410);
FORCEPROP 2 LASTPIN (-6475 3350) $PN AA32
J 2
(-6485 3360);
DISPLAY 0.617021 (-6485 3360);
PAINT ORANGE (-6485 3360);
FORCEPROP 2 LASTPIN (-6475 3300) $PN AA34
J 2
(-6485 3310);
DISPLAY 0.617021 (-6485 3310);
PAINT ORANGE (-6485 3310);
FORCEPROP 2 LASTPIN (-6475 3250) $PN AA36
J 2
(-6485 3260);
DISPLAY 0.617021 (-6485 3260);
PAINT ORANGE (-6485 3260);
FORCEPROP 2 LASTPIN (-6475 3200) $PN AA37
J 2
(-6485 3210);
DISPLAY 0.617021 (-6485 3210);
PAINT ORANGE (-6485 3210);
FORCEPROP 2 LASTPIN (-6475 3150) $PN AA39
J 2
(-6485 3160);
DISPLAY 0.617021 (-6485 3160);
PAINT ORANGE (-6485 3160);
FORCEPROP 2 LASTPIN (-6475 3100) $PN AA41
J 2
(-6485 3110);
DISPLAY 0.617021 (-6485 3110);
PAINT ORANGE (-6485 3110);
FORCEPROP 2 LASTPIN (-6475 3050) $PN AC29
J 2
(-6485 3060);
DISPLAY 0.617021 (-6485 3060);
PAINT ORANGE (-6485 3060);
FORCEPROP 2 LASTPIN (-6475 3000) $PN AC30
J 2
(-6485 3010);
DISPLAY 0.617021 (-6485 3010);
PAINT ORANGE (-6485 3010);
FORCEPROP 2 LASTPIN (-6475 2950) $PN AC32
J 2
(-6485 2960);
DISPLAY 0.617021 (-6485 2960);
PAINT ORANGE (-6485 2960);
FORCEPROP 2 LASTPIN (-6475 2900) $PN AC34
J 2
(-6485 2910);
DISPLAY 0.617021 (-6485 2910);
PAINT ORANGE (-6485 2910);
FORCEPROP 2 LASTPIN (-6475 2850) $PN AC36
J 2
(-6485 2860);
DISPLAY 0.617021 (-6485 2860);
PAINT ORANGE (-6485 2860);
FORCEPROP 2 LASTPIN (-6475 2800) $PN AC37
J 2
(-6485 2810);
DISPLAY 0.617021 (-6485 2810);
PAINT ORANGE (-6485 2810);
FORCEPROP 2 LASTPIN (-6475 2750) $PN AC39
J 2
(-6485 2760);
DISPLAY 0.617021 (-6485 2760);
PAINT ORANGE (-6485 2760);
FORCEPROP 2 LASTPIN (-6475 2700) $PN AC41
J 2
(-6485 2710);
DISPLAY 0.617021 (-6485 2710);
PAINT ORANGE (-6485 2710);
FORCEPROP 2 LASTPIN (-4275 4100) $PN U27
J 0
(-4265 4110);
DISPLAY 0.617021 (-4265 4110);
PAINT ORANGE (-4265 4110);
FORCEPROP 2 LASTPIN (-6475 2600) $PN AE30
J 2
(-6485 2610);
DISPLAY 0.617021 (-6485 2610);
PAINT ORANGE (-6485 2610);
FORCEPROP 2 LASTPIN (-6475 2550) $PN AE32
J 2
(-6485 2560);
DISPLAY 0.617021 (-6485 2560);
PAINT ORANGE (-6485 2560);
FORCEPROP 2 LASTPIN (-6475 2500) $PN AE34
J 2
(-6485 2510);
DISPLAY 0.617021 (-6485 2510);
PAINT ORANGE (-6485 2510);
FORCEPROP 2 LASTPIN (-6475 2450) $PN AE36
J 2
(-6485 2460);
DISPLAY 0.617021 (-6485 2460);
PAINT ORANGE (-6485 2460);
FORCEPROP 2 LASTPIN (-6475 2400) $PN AE37
J 2
(-6485 2410);
DISPLAY 0.617021 (-6485 2410);
PAINT ORANGE (-6485 2410);
FORCEPROP 2 LASTPIN (-6475 2350) $PN AE39
J 2
(-6485 2360);
DISPLAY 0.617021 (-6485 2360);
PAINT ORANGE (-6485 2360);
FORCEPROP 2 LASTPIN (-6475 2300) $PN AE41
J 2
(-6485 2310);
DISPLAY 0.617021 (-6485 2310);
PAINT ORANGE (-6485 2310);
FORCEPROP 2 LASTPIN (-6475 2250) $PN AG32
J 2
(-6485 2260);
DISPLAY 0.617021 (-6485 2260);
PAINT ORANGE (-6485 2260);
FORCEPROP 2 LASTPIN (-6475 2200) $PN AG34
J 2
(-6485 2210);
DISPLAY 0.617021 (-6485 2210);
PAINT ORANGE (-6485 2210);
FORCEPROP 2 LASTPIN (-6475 2150) $PN AG36
J 2
(-6485 2160);
DISPLAY 0.617021 (-6485 2160);
PAINT ORANGE (-6485 2160);
FORCEPROP 2 LASTPIN (-6475 2100) $PN AG37
J 2
(-6485 2110);
DISPLAY 0.617021 (-6485 2110);
PAINT ORANGE (-6485 2110);
FORCEPROP 2 LASTPIN (-6475 2050) $PN AG39
J 2
(-6485 2060);
DISPLAY 0.617021 (-6485 2060);
PAINT ORANGE (-6485 2060);
FORCEPROP 2 LASTPIN (-6475 2000) $PN AK34
J 2
(-6485 2010);
DISPLAY 0.617021 (-6485 2010);
PAINT ORANGE (-6485 2010);
FORCEPROP 2 LASTPIN (-6475 1950) $PN AK37
J 2
(-6485 1960);
DISPLAY 0.617021 (-6485 1960);
PAINT ORANGE (-6485 1960);
FORCEPROP 2 LASTPIN (-6475 1900) $PN AK39
J 2
(-6485 1910);
DISPLAY 0.617021 (-6485 1910);
PAINT ORANGE (-6485 1910);
FORCEPROP 2 LASTPIN (-6475 1850) $PN AM32
J 2
(-6485 1860);
DISPLAY 0.617021 (-6485 1860);
PAINT ORANGE (-6485 1860);
FORCEPROP 2 LASTPIN (-6475 1800) $PN AM34
J 2
(-6485 1810);
DISPLAY 0.617021 (-6485 1810);
PAINT ORANGE (-6485 1810);
FORCEPROP 2 LASTPIN (-6475 1750) $PN AM36
J 2
(-6485 1760);
DISPLAY 0.617021 (-6485 1760);
PAINT ORANGE (-6485 1760);
FORCEPROP 2 LASTPIN (-6475 1700) $PN AM37
J 2
(-6485 1710);
DISPLAY 0.617021 (-6485 1710);
PAINT ORANGE (-6485 1710);
FORCEPROP 2 LASTPIN (-6475 1650) $PN AM39
J 2
(-6485 1660);
DISPLAY 0.617021 (-6485 1660);
PAINT ORANGE (-6485 1660);
FORCEPROP 2 LASTPIN (-6475 1600) $PN AP32
J 2
(-6485 1610);
DISPLAY 0.617021 (-6485 1610);
PAINT ORANGE (-6485 1610);
FORCEPROP 2 LASTPIN (-6475 1550) $PN AP34
J 2
(-6485 1560);
DISPLAY 0.617021 (-6485 1560);
PAINT ORANGE (-6485 1560);
FORCEPROP 2 LASTPIN (-6475 1500) $PN AP36
J 2
(-6485 1510);
DISPLAY 0.617021 (-6485 1510);
PAINT ORANGE (-6485 1510);
FORCEPROP 2 LASTPIN (-6475 1450) $PN AP37
J 2
(-6485 1460);
DISPLAY 0.617021 (-6485 1460);
PAINT ORANGE (-6485 1460);
FORCEPROP 2 LASTPIN (-6475 1400) $PN AP39
J 2
(-6485 1410);
DISPLAY 0.617021 (-6485 1410);
PAINT ORANGE (-6485 1410);
FORCEPROP 2 LASTPIN (-6475 1350) $PN AT32
J 2
(-6485 1360);
DISPLAY 0.617021 (-6485 1360);
PAINT ORANGE (-6485 1360);
FORCEPROP 2 LASTPIN (-6475 1300) $PN AT34
J 2
(-6485 1310);
DISPLAY 0.617021 (-6485 1310);
PAINT ORANGE (-6485 1310);
FORCEPROP 2 LASTPIN (-6475 1250) $PN AT36
J 2
(-6485 1260);
DISPLAY 0.617021 (-6485 1260);
PAINT ORANGE (-6485 1260);
FORCEPROP 2 LASTPIN (-6475 1200) $PN AU32
J 2
(-6485 1210);
DISPLAY 0.617021 (-6485 1210);
PAINT ORANGE (-6485 1210);
FORCEPROP 2 LASTPIN (-6475 1150) $PN AU34
J 2
(-6485 1160);
DISPLAY 0.617021 (-6485 1160);
PAINT ORANGE (-6485 1160);
FORCEPROP 2 LASTPIN (-6475 1100) $PN AU36
J 2
(-6485 1110);
DISPLAY 0.617021 (-6485 1110);
PAINT ORANGE (-6485 1110);
FORCEPROP 2 LASTPIN (-4275 4050) $PN V37
J 0
(-4265 4060);
DISPLAY 0.617021 (-4265 4060);
PAINT ORANGE (-4265 4060);
FORCEPROP 2 LASTPIN (-4275 3950) $PN AK36
J 0
(-4265 3960);
DISPLAY 0.617021 (-4265 3960);
PAINT ORANGE (-4265 3960);
FORCEPROP 2 LASTPIN (-6475 4000) $PN V29
J 2
(-6485 4010);
DISPLAY 0.617021 (-6485 4010);
PAINT ORANGE (-6485 4010);
FORCEPROP 1 LAST PACK_TYPE BGA1
J 0
(-6425 4450);
PAINT SKYBLUE (-6425 4450);
DISPLAY INVISIBLE (-6425 4450);
FORCEPROP 2 LAST SEC_TYPE BGA1
J 0
(-6100 4475);
DISPLAY 1.021277 (-6100 4475);
PAINT ORANGE (-6100 4475);
DISPLAY INVISIBLE (-6100 4475);
FORCEPROP 2 LAST SEC 10
J 0
(-6100 4475);
DISPLAY 0.680851 (-6100 4475);
PAINT MONO (-6100 4475);
DISPLAY INVISIBLE (-6100 4475);
FORCEPROP 2 LAST CDS_LIB mstr_u_proc
J 0
(-5375 2600);
PAINT ORANGE (-5375 2600);
DISPLAY INVISIBLE (-5375 2600);
FORCEPROP 0 LAST BOM_COST SB
J 0
(-6625 4400);
DISPLAY 1.361702 (-6625 4400);
PAINT ORANGE (-6625 4400);
DISPLAY INVISIBLE (-6625 4400);
FORCEPROP 2 LAST CDS_LOCATION U7C1
J 0
(-6100 4425);
DISPLAY 0.617021 (-6100 4425);
PAINT AQUA (-6100 4425);
DISPLAY INVISIBLE (-6100 4425);
FORCEPROP 1 LAST PATH I21
J 0
(-5375 4350);
PAINT GREEN (-5375 4350);
DISPLAY INVISIBLE (-5375 4350);
FORCEPROP 0 LAST ROOM SB
J 0
(-6100 4525);
DISPLAY 1.021277 (-6100 4525);
PAINT ORANGE (-6100 4525);
DISPLAY INVISIBLE (-6100 4525);
FORCEADD OFFPAGE..2
(-3350 4050);
FORCEPROP 2 LAST $XR0 236 
J 0
(-3161 4050);
DISPLAY 0.638298 (-3161 4050);
PAINT MONO (-3161 4050);
FORCEPROP 2 LAST CDS_LIB mstr_standard
J 0
(-3350 4050);
PAINT MONO (-3350 4050);
DISPLAY INVISIBLE (-3350 4050);
FORCEPROP 1 LAST OFFPAGE TRUE
J 0
(-3025 3925);
DISPLAY 1.170213 (-3025 3925);
PAINT GREEN (-3025 3925);
DISPLAY INVISIBLE (-3025 3925);
FORCEPROP 1 LAST COMMENT_BODY TRUE
J 0
(-3395 3955);
DISPLAY 1.170213 (-3395 3955);
PAINT GREEN (-3395 3955);
DISPLAY INVISIBLE (-3395 3955);
FORCEPROP 2 LAST PATH I22
J 0
(-3175 4125);
DISPLAY 1.021277 (-3175 4125);
PAINT ORANGE (-3175 4125);
DISPLAY INVISIBLE (-3175 4125);
FORCEADD OFFPAGE..2
(-3350 3950);
FORCEPROP 2 LAST $XR0 236 
J 0
(-3161 3950);
DISPLAY 0.638298 (-3161 3950);
PAINT MONO (-3161 3950);
FORCEPROP 2 LAST CDS_LIB mstr_standard
J 0
(-3350 3950);
PAINT MONO (-3350 3950);
DISPLAY INVISIBLE (-3350 3950);
FORCEPROP 1 LAST OFFPAGE TRUE
J 0
(-3025 3825);
DISPLAY 1.170213 (-3025 3825);
PAINT GREEN (-3025 3825);
DISPLAY INVISIBLE (-3025 3825);
FORCEPROP 1 LAST COMMENT_BODY TRUE
J 0
(-3395 3855);
DISPLAY 1.170213 (-3395 3855);
PAINT GREEN (-3395 3855);
DISPLAY INVISIBLE (-3395 3855);
FORCEPROP 2 LAST PATH I23
J 0
(-3175 4025);
DISPLAY 1.021277 (-3175 4025);
PAINT ORANGE (-3175 4025);
DISPLAY INVISIBLE (-3175 4025);
FORCEADD PVNN_PCH_STBY..1
(-3850 4375);
FORCEPROP 3 LASTPIN (-3850 4325) SIG_NAME PVNN_PCH_STBY\g
J 0
(-3840 4335);
DISPLAY 0.659574 (-3840 4335);
PAINT MONO (-3840 4335);
DISPLAY INVISIBLE (-3840 4335);
FORCEPROP 1 LAST VOLTAGE 1.0V
J 0
(-3895 4332);
DISPLAY 0.340426 (-3895 4332);
PAINT SKYBLUE (-3895 4332);
DISPLAY INVISIBLE (-3895 4332);
FORCEPROP 2 LAST CDS_LIB mstr_symbols
J 0
(-3850 4375);
PAINT ORANGE (-3850 4375);
DISPLAY INVISIBLE (-3850 4375);
FORCEPROP 1 LAST BODY_TYPE PLUMBING
J 0
(-3895 4332);
DISPLAY 0.340426 (-3895 4332);
PAINT GREEN (-3895 4332);
DISPLAY INVISIBLE (-3895 4332);
FORCEPROP 1 LAST PATH I24
J 0
(-3800 4400);
DISPLAY 0.872340 (-3800 4400);
PAINT AQUA (-3800 4400);
DISPLAY INVISIBLE (-3800 4400);
FORCEPROP 1 LAST HDL_POWER PVNN_PCH_STBY
J 1
(-3850 4425);
DISPLAY 0.872340 (-3850 4425);
PAINT GREEN (-3850 4425);
DISPLAY INVISIBLE (-3850 4425);
FORCEADD P1V05_PCH_STBY..1
(-7425 2800);
FORCEPROP 3 LASTPIN (-7425 2750) SIG_NAME P1V05_PCH_STBY\g
J 0
(-7415 2760);
DISPLAY 0.659574 (-7415 2760);
PAINT MONO (-7415 2760);
DISPLAY INVISIBLE (-7415 2760);
FORCEPROP 1 LAST VOLTAGE 1.05V
J 0
(-7470 2757);
DISPLAY 0.340426 (-7470 2757);
PAINT SKYBLUE (-7470 2757);
DISPLAY INVISIBLE (-7470 2757);
FORCEPROP 2 LAST CDS_LIB mstr_symbols
J 0
(-7425 2800);
PAINT ORANGE (-7425 2800);
DISPLAY INVISIBLE (-7425 2800);
FORCEPROP 1 LAST BODY_TYPE PLUMBING
J 0
(-7470 2757);
DISPLAY 0.340426 (-7470 2757);
PAINT GREEN (-7470 2757);
DISPLAY INVISIBLE (-7470 2757);
FORCEPROP 1 LAST PATH I25
J 0
(-7375 2825);
DISPLAY 0.872340 (-7375 2825);
PAINT AQUA (-7375 2825);
DISPLAY INVISIBLE (-7375 2825);
FORCEPROP 1 LAST HDL_POWER P1V05_PCH_STBY
J 0
(-7425 2850);
DISPLAY 0.872340 (-7425 2850);
PAINT GREEN (-7425 2850);
DISPLAY INVISIBLE (-7425 2850);
FORCEADD INTEL_CORP_BPAGE..1
(0 0);
FORCEPROP 1 LAST CDS_CON_LAST_MODIFIED Fri Jun 16 17:48:48 2017
J 0
(-1425 325);
DISPLAY 1.340426 (-1425 325);
PAINT GREEN (-1425 325);
DISPLAY INVISIBLE (-1425 325);
FORCEPROP 1 LAST CUSTOM_TXT_CDS <CURRENT_DESIGN_SHEET> OF <TOTAL_DESIGN_SHEETS>
J 0
(-500 25);
PAINT ORANGE (-500 25);
FORCEPROP 1 LAST CUSTOM_TXT_CDS <CON_LAST_MODIFIED>
J 0
(-4000 100);
PAINT ORANGE (-4000 100);
FORCEPROP 2 LAST CUSTOM_TXT_CDS <XR_PAGE_TITLE>
J 0
(-7890 5250);
DISPLAY 0.638298 (-7890 5250);
PAINT PINK (-7890 5250);
DISPLAY INVISIBLE (-7890 5250);
FORCEPROP 1 LAST SCH_TITLE LEWISBURG 10/11 PWR, GND
J 0
(-7950 50);
DISPLAY 1.212766 (-7950 50);
PAINT GREEN (-7950 50);
FORCEPROP 2 LAST CDS_LIB mstr_symbols
J 0
(0 0);
PAINT ORANGE (0 0);
DISPLAY INVISIBLE (0 0);
FORCEPROP 2 LAST PAGE_BORDER TRUE
J 0
(-7890 5250);
DISPLAY 0.851064 (-7890 5250);
PAINT PINK (-7890 5250);
DISPLAY INVISIBLE (-7890 5250);
FORCEPROP 1 LAST COMMENT_BODY TRUE
J 0
(12 12);
DISPLAY 0.638298 (12 12);
PAINT GREEN (12 12);
DISPLAY INVISIBLE (12 12);
FORCEPROP 2 LAST CDS_XR_PAGE_TITLE CR-123 : @BASEBOARD_FAB2_LIB.BASEBOARD_FAB2(SCH_1):PAGE123
J 0
(-7890 5250);
DISPLAY 0.638298 (-7890 5250);
PAINT PINK (-7890 5250);
DISPLAY INVISIBLE (-7890 5250);
WIRE 16 -1 (-375 700)(-375 825);
WIRE 16 -1 (-375 825)(-375 875);
WIRE 16 -1 (-1025 825)(-375 825);
WIRE 16 -1 (-375 925)(-375 875);
WIRE 16 -1 (-1025 875)(-375 875);
WIRE 16 -1 (-375 975)(-375 925);
WIRE 16 -1 (-375 925)(-1025 925);
WIRE 16 -1 (-375 1025)(-375 975);
WIRE 16 -1 (-1025 975)(-375 975);
WIRE 16 -1 (-375 1075)(-375 1025);
WIRE 16 -1 (-1025 1025)(-375 1025);
WIRE 16 -1 (-375 1125)(-375 1075);
WIRE 16 -1 (-1025 1075)(-375 1075);
WIRE 16 -1 (-375 1175)(-375 1125);
WIRE 16 -1 (-375 1125)(-1025 1125);
WIRE 16 -1 (-375 1225)(-375 1175);
WIRE 16 -1 (-1025 1175)(-375 1175);
WIRE 16 -1 (-375 1275)(-375 1225);
WIRE 16 -1 (-1025 1225)(-375 1225);
WIRE 16 -1 (-375 1325)(-375 1275);
WIRE 16 -1 (-1025 1275)(-375 1275);
WIRE 16 -1 (-375 1375)(-375 1325);
WIRE 16 -1 (-375 1325)(-1025 1325);
WIRE 16 -1 (-375 1425)(-375 1375);
WIRE 16 -1 (-1025 1375)(-375 1375);
WIRE 16 -1 (-375 1475)(-375 1425);
WIRE 16 -1 (-1025 1425)(-375 1425);
WIRE 16 -1 (-375 1525)(-375 1475);
WIRE 16 -1 (-1025 1475)(-375 1475);
WIRE 16 -1 (-375 1575)(-375 1525);
WIRE 16 -1 (-1025 1525)(-375 1525);
WIRE 16 -1 (-375 1625)(-375 1575);
WIRE 16 -1 (-375 1575)(-1025 1575);
WIRE 16 -1 (-375 1675)(-375 1625);
WIRE 16 -1 (-1025 1625)(-375 1625);
WIRE 16 -1 (-375 1725)(-375 1675);
WIRE 16 -1 (-1025 1675)(-375 1675);
WIRE 16 -1 (-375 1775)(-375 1725);
WIRE 16 -1 (-1025 1725)(-375 1725);
WIRE 16 -1 (-375 1825)(-375 1775);
WIRE 16 -1 (-1025 1775)(-375 1775);
WIRE 16 -1 (-375 1875)(-375 1825);
WIRE 16 -1 (-1025 1825)(-375 1825);
WIRE 16 -1 (-375 1925)(-375 1875);
WIRE 16 -1 (-375 1875)(-1025 1875);
WIRE 16 -1 (-375 1975)(-375 1925);
WIRE 16 -1 (-1025 1925)(-375 1925);
WIRE 16 -1 (-375 2025)(-375 1975);
WIRE 16 -1 (-1025 1975)(-375 1975);
WIRE 16 -1 (-375 2075)(-375 2025);
WIRE 16 -1 (-1025 2025)(-375 2025);
WIRE 16 -1 (-375 2125)(-375 2075);
WIRE 16 -1 (-1025 2075)(-375 2075);
WIRE 16 -1 (-375 2175)(-375 2125);
WIRE 16 -1 (-1025 2125)(-375 2125);
WIRE 16 -1 (-375 2225)(-375 2175);
WIRE 16 -1 (-1025 2175)(-375 2175);
WIRE 16 -1 (-375 2275)(-375 2225);
WIRE 16 -1 (-1025 2225)(-375 2225);
WIRE 16 -1 (-375 2325)(-375 2275);
WIRE 16 -1 (-1025 2275)(-375 2275);
WIRE 16 -1 (-375 2375)(-375 2325);
WIRE 16 -1 (-1025 2325)(-375 2325);
WIRE 16 -1 (-375 2425)(-375 2375);
WIRE 16 -1 (-1025 2375)(-375 2375);
WIRE 16 -1 (-375 2475)(-375 2425);
WIRE 16 -1 (-1025 2425)(-375 2425);
WIRE 16 -1 (-375 2525)(-375 2475);
WIRE 16 -1 (-1025 2475)(-375 2475);
WIRE 16 -1 (-375 2575)(-375 2525);
WIRE 16 -1 (-1025 2525)(-375 2525);
WIRE 16 -1 (-375 2625)(-375 2575);
WIRE 16 -1 (-1025 2575)(-375 2575);
WIRE 16 -1 (-375 2675)(-375 2625);
WIRE 16 -1 (-1025 2625)(-375 2625);
WIRE 16 -1 (-375 2725)(-375 2675);
WIRE 16 -1 (-1025 2675)(-375 2675);
WIRE 16 -1 (-375 2775)(-375 2725);
WIRE 16 -1 (-1025 2725)(-375 2725);
WIRE 16 -1 (-375 2825)(-375 2775);
WIRE 16 -1 (-1025 2775)(-375 2775);
WIRE 16 -1 (-375 2875)(-375 2825);
WIRE 16 -1 (-1025 2825)(-375 2825);
WIRE 16 -1 (-375 2925)(-375 2875);
WIRE 16 -1 (-1025 2875)(-375 2875);
WIRE 16 -1 (-375 2975)(-375 2925);
WIRE 16 -1 (-1025 2925)(-375 2925);
WIRE 16 -1 (-375 3025)(-375 2975);
WIRE 16 -1 (-1025 2975)(-375 2975);
WIRE 16 -1 (-375 3075)(-375 3025);
WIRE 16 -1 (-1025 3025)(-375 3025);
WIRE 16 -1 (-375 3125)(-375 3075);
WIRE 16 -1 (-1025 3075)(-375 3075);
WIRE 16 -1 (-375 3175)(-375 3125);
WIRE 16 -1 (-1025 3125)(-375 3125);
WIRE 16 -1 (-375 3225)(-375 3175);
WIRE 16 -1 (-1025 3175)(-375 3175);
WIRE 16 -1 (-375 3275)(-375 3225);
WIRE 16 -1 (-1025 3225)(-375 3225);
WIRE 16 -1 (-375 3325)(-375 3275);
WIRE 16 -1 (-1025 3275)(-375 3275);
WIRE 16 -1 (-375 3375)(-375 3325);
WIRE 16 -1 (-1025 3325)(-375 3325);
WIRE 16 -1 (-375 3425)(-375 3375);
WIRE 16 -1 (-1025 3375)(-375 3375);
WIRE 16 -1 (-375 3475)(-375 3425);
WIRE 16 -1 (-1025 3425)(-375 3425);
WIRE 16 -1 (-375 3525)(-375 3475);
WIRE 16 -1 (-1025 3475)(-375 3475);
WIRE 16 -1 (-375 3575)(-375 3525);
WIRE 16 -1 (-1025 3525)(-375 3525);
WIRE 16 -1 (-375 3625)(-375 3575);
WIRE 16 -1 (-375 3575)(-1025 3575);
WIRE 16 -1 (-375 3675)(-375 3625);
WIRE 16 -1 (-1025 3625)(-375 3625);
WIRE 16 -1 (-375 3725)(-375 3675);
WIRE 16 -1 (-1025 3675)(-375 3675);
WIRE 16 -1 (-375 3775)(-375 3725);
WIRE 16 -1 (-1025 3725)(-375 3725);
WIRE 16 -1 (-375 3825)(-375 3775);
WIRE 16 -1 (-1025 3775)(-375 3775);
WIRE 16 -1 (-375 3875)(-375 3825);
WIRE 16 -1 (-375 3825)(-1025 3825);
WIRE 16 -1 (-375 3925)(-375 3875);
WIRE 16 -1 (-1025 3875)(-375 3875);
WIRE 16 -1 (-375 3975)(-375 3925);
WIRE 16 -1 (-1025 3925)(-375 3925);
WIRE 16 -1 (-375 4025)(-375 3975);
WIRE 16 -1 (-1025 3975)(-375 3975);
WIRE 16 -1 (-375 4075)(-375 4025);
WIRE 16 -1 (-1025 4025)(-375 4025);
WIRE 16 -1 (-375 4125)(-375 4075);
WIRE 16 -1 (-375 4075)(-1025 4075);
WIRE 16 -1 (-375 4175)(-375 4125);
WIRE 16 -1 (-1025 4125)(-375 4125);
WIRE 16 -1 (-375 4225)(-375 4175);
WIRE 16 -1 (-1025 4175)(-375 4175);
WIRE 16 -1 (-375 4275)(-375 4225);
WIRE 16 -1 (-1025 4225)(-375 4225);
WIRE 16 -1 (-1025 4275)(-375 4275);
WIRE 16 -1 (-2800 825)(-2800 700);
WIRE 16 -1 (-2800 875)(-2800 825);
WIRE 16 -1 (-2225 825)(-2800 825);
WIRE 16 -1 (-2800 925)(-2800 875);
WIRE 16 -1 (-2800 875)(-2225 875);
WIRE 16 -1 (-2800 975)(-2800 925);
WIRE 16 -1 (-2800 925)(-2225 925);
WIRE 16 -1 (-2800 1025)(-2800 975);
WIRE 16 -1 (-2800 975)(-2225 975);
WIRE 16 -1 (-2800 1075)(-2800 1025);
WIRE 16 -1 (-2225 1025)(-2800 1025);
WIRE 16 -1 (-2800 1125)(-2800 1075);
WIRE 16 -1 (-2225 1075)(-2800 1075);
WIRE 16 -1 (-2800 1175)(-2800 1125);
WIRE 16 -1 (-2225 1125)(-2800 1125);
WIRE 16 -1 (-2800 1225)(-2800 1175);
WIRE 16 -1 (-2225 1175)(-2800 1175);
WIRE 16 -1 (-2800 1275)(-2800 1225);
WIRE 16 -1 (-2225 1225)(-2800 1225);
WIRE 16 -1 (-2800 1325)(-2800 1275);
WIRE 16 -1 (-2225 1275)(-2800 1275);
WIRE 16 -1 (-2800 1375)(-2800 1325);
WIRE 16 -1 (-2225 1325)(-2800 1325);
WIRE 16 -1 (-2800 1425)(-2800 1375);
WIRE 16 -1 (-2225 1375)(-2800 1375);
WIRE 16 -1 (-2800 1475)(-2800 1425);
WIRE 16 -1 (-2225 1425)(-2800 1425);
WIRE 16 -1 (-2800 1525)(-2800 1475);
WIRE 16 -1 (-2225 1475)(-2800 1475);
WIRE 16 -1 (-2800 1575)(-2800 1525);
WIRE 16 -1 (-2225 1525)(-2800 1525);
WIRE 16 -1 (-2800 1625)(-2800 1575);
WIRE 16 -1 (-2225 1575)(-2800 1575);
WIRE 16 -1 (-2800 1675)(-2800 1625);
WIRE 16 -1 (-2225 1625)(-2800 1625);
WIRE 16 -1 (-2800 1725)(-2800 1675);
WIRE 16 -1 (-2225 1675)(-2800 1675);
WIRE 16 -1 (-2800 1775)(-2800 1725);
WIRE 16 -1 (-2800 1725)(-2225 1725);
WIRE 16 -1 (-2800 1825)(-2800 1775);
WIRE 16 -1 (-2800 1775)(-2225 1775);
WIRE 16 -1 (-2800 1875)(-2800 1825);
WIRE 16 -1 (-2225 1825)(-2800 1825);
WIRE 16 -1 (-2800 1925)(-2800 1875);
WIRE 16 -1 (-2800 1875)(-2225 1875);
WIRE 16 -1 (-2800 1975)(-2800 1925);
WIRE 16 -1 (-2800 1925)(-2225 1925);
WIRE 16 -1 (-2800 2025)(-2800 1975);
WIRE 16 -1 (-2800 1975)(-2225 1975);
WIRE 16 -1 (-2800 2075)(-2800 2025);
WIRE 16 -1 (-2800 2025)(-2225 2025);
WIRE 16 -1 (-2800 2125)(-2800 2075);
WIRE 16 -1 (-2800 2075)(-2225 2075);
WIRE 16 -1 (-2800 2175)(-2800 2125);
WIRE 16 -1 (-2800 2125)(-2225 2125);
WIRE 16 -1 (-2800 2225)(-2800 2175);
WIRE 16 -1 (-2225 2175)(-2800 2175);
WIRE 16 -1 (-2800 2275)(-2800 2225);
WIRE 16 -1 (-2800 2225)(-2225 2225);
WIRE 16 -1 (-2800 2325)(-2800 2275);
WIRE 16 -1 (-2800 2275)(-2225 2275);
WIRE 16 -1 (-2800 2375)(-2800 2325);
WIRE 16 -1 (-2800 2325)(-2225 2325);
WIRE 16 -1 (-2800 2425)(-2800 2375);
WIRE 16 -1 (-2225 2375)(-2800 2375);
WIRE 16 -1 (-2800 2475)(-2800 2425);
WIRE 16 -1 (-2800 2425)(-2225 2425);
WIRE 16 -1 (-2800 2525)(-2800 2475);
WIRE 16 -1 (-2800 2475)(-2225 2475);
WIRE 16 -1 (-2800 2575)(-2800 2525);
WIRE 16 -1 (-2225 2525)(-2800 2525);
WIRE 16 -1 (-2800 2625)(-2800 2575);
WIRE 16 -1 (-2225 2575)(-2800 2575);
WIRE 16 -1 (-2800 2675)(-2800 2625);
WIRE 16 -1 (-2800 2625)(-2225 2625);
WIRE 16 -1 (-2800 2725)(-2800 2675);
WIRE 16 -1 (-2800 2675)(-2225 2675);
WIRE 16 -1 (-2800 2775)(-2800 2725);
WIRE 16 -1 (-2225 2725)(-2800 2725);
WIRE 16 -1 (-2800 2825)(-2800 2775);
WIRE 16 -1 (-2800 2775)(-2225 2775);
WIRE 16 -1 (-2800 2875)(-2800 2825);
WIRE 16 -1 (-2800 2825)(-2225 2825);
WIRE 16 -1 (-2800 2925)(-2800 2875);
WIRE 16 -1 (-2225 2875)(-2800 2875);
WIRE 16 -1 (-2800 2975)(-2800 2925);
WIRE 16 -1 (-2800 2925)(-2225 2925);
WIRE 16 -1 (-2800 3025)(-2800 2975);
WIRE 16 -1 (-2800 2975)(-2225 2975);
WIRE 16 -1 (-2800 3075)(-2800 3025);
WIRE 16 -1 (-2800 3025)(-2225 3025);
WIRE 16 -1 (-2800 3125)(-2800 3075);
WIRE 16 -1 (-2800 3075)(-2225 3075);
WIRE 16 -1 (-2800 3175)(-2800 3125);
WIRE 16 -1 (-2800 3125)(-2225 3125);
WIRE 16 -1 (-2800 3225)(-2800 3175);
WIRE 16 -1 (-2800 3175)(-2225 3175);
WIRE 16 -1 (-2800 3275)(-2800 3225);
WIRE 16 -1 (-2800 3225)(-2225 3225);
WIRE 16 -1 (-2800 3325)(-2800 3275);
WIRE 16 -1 (-2800 3275)(-2225 3275);
WIRE 16 -1 (-2800 3375)(-2800 3325);
WIRE 16 -1 (-2800 3325)(-2225 3325);
WIRE 16 -1 (-2800 3425)(-2800 3375);
WIRE 16 -1 (-2800 3375)(-2225 3375);
WIRE 16 -1 (-2800 3475)(-2800 3425);
WIRE 16 -1 (-2225 3425)(-2800 3425);
WIRE 16 -1 (-2800 3525)(-2800 3475);
WIRE 16 -1 (-2800 3475)(-2225 3475);
WIRE 16 -1 (-2800 3575)(-2800 3525);
WIRE 16 -1 (-2800 3525)(-2225 3525);
WIRE 16 -1 (-2800 3625)(-2800 3575);
WIRE 16 -1 (-2225 3575)(-2800 3575);
WIRE 16 -1 (-2800 3675)(-2800 3625);
WIRE 16 -1 (-2225 3625)(-2800 3625);
WIRE 16 -1 (-2800 3725)(-2800 3675);
WIRE 16 -1 (-2225 3675)(-2800 3675);
WIRE 16 -1 (-2800 3775)(-2800 3725);
WIRE 16 -1 (-2225 3725)(-2800 3725);
WIRE 16 -1 (-2800 3825)(-2800 3775);
WIRE 16 -1 (-2225 3775)(-2800 3775);
WIRE 16 -1 (-2800 3875)(-2800 3825);
WIRE 16 -1 (-2225 3825)(-2800 3825);
WIRE 16 -1 (-2800 3925)(-2800 3875);
WIRE 16 -1 (-2225 3875)(-2800 3875);
WIRE 16 -1 (-2800 3975)(-2800 3925);
WIRE 16 -1 (-2225 3925)(-2800 3925);
WIRE 16 -1 (-2800 4025)(-2800 3975);
WIRE 16 -1 (-2225 3975)(-2800 3975);
WIRE 16 -1 (-2800 4075)(-2800 4025);
WIRE 16 -1 (-2225 4025)(-2800 4025);
WIRE 16 -1 (-2800 4125)(-2800 4075);
WIRE 16 -1 (-2800 4075)(-2225 4075);
WIRE 16 -1 (-2800 4175)(-2800 4125);
WIRE 16 -1 (-2225 4125)(-2800 4125);
WIRE 16 -1 (-2800 4225)(-2800 4175);
WIRE 16 -1 (-2800 4175)(-2225 4175);
WIRE 16 -1 (-2800 4275)(-2800 4225);
WIRE 16 -1 (-2800 4225)(-2225 4225);
WIRE 16 -1 (-2225 4275)(-2800 4275);
WIRE 16 -1 (-6900 4350)(-6900 4150);
WIRE 16 -1 (-6900 4150)(-6900 4100);
WIRE 16 -1 (-6900 4150)(-6475 4150);
WIRE 16 -1 (-6900 4100)(-6900 4050);
WIRE 16 -1 (-6475 4100)(-6900 4100);
WIRE 16 -1 (-6900 4050)(-6900 4000);
WIRE 16 -1 (-6475 4050)(-6900 4050);
WIRE 16 -1 (-6900 4000)(-6900 3950);
WIRE 16 -1 (-6475 4000)(-6900 4000);
WIRE 16 -1 (-6900 3950)(-6900 3900);
WIRE 16 -1 (-6475 3950)(-6900 3950);
WIRE 16 -1 (-6900 3900)(-6900 3850);
WIRE 16 -1 (-6475 3900)(-6900 3900);
WIRE 16 -1 (-6900 3850)(-6900 3800);
WIRE 16 -1 (-6475 3850)(-6900 3850);
WIRE 16 -1 (-6900 3800)(-6900 3750);
WIRE 16 -1 (-6475 3800)(-6900 3800);
WIRE 16 -1 (-6900 3750)(-6900 3700);
WIRE 16 -1 (-6475 3750)(-6900 3750);
WIRE 16 -1 (-6900 3700)(-6900 3650);
WIRE 16 -1 (-6475 3700)(-6900 3700);
WIRE 16 -1 (-6900 3650)(-6900 3600);
WIRE 16 -1 (-6475 3650)(-6900 3650);
WIRE 16 -1 (-6900 3600)(-6900 3550);
WIRE 16 -1 (-6475 3600)(-6900 3600);
WIRE 16 -1 (-6900 3550)(-6900 3500);
WIRE 16 -1 (-6475 3550)(-6900 3550);
WIRE 16 -1 (-6900 3500)(-6900 3450);
WIRE 16 -1 (-6475 3500)(-6900 3500);
WIRE 16 -1 (-6900 3450)(-6900 3400);
WIRE 16 -1 (-6475 3450)(-6900 3450);
WIRE 16 -1 (-6900 3400)(-6900 3350);
WIRE 16 -1 (-6475 3400)(-6900 3400);
WIRE 16 -1 (-6900 3350)(-6900 3300);
WIRE 16 -1 (-6475 3350)(-6900 3350);
WIRE 16 -1 (-6900 3300)(-6900 3250);
WIRE 16 -1 (-6475 3300)(-6900 3300);
WIRE 16 -1 (-6900 3250)(-6900 3200);
WIRE 16 -1 (-6475 3250)(-6900 3250);
WIRE 16 -1 (-6900 3200)(-6900 3150);
WIRE 16 -1 (-6475 3200)(-6900 3200);
WIRE 16 -1 (-6900 3150)(-6900 3100);
WIRE 16 -1 (-6475 3150)(-6900 3150);
WIRE 16 -1 (-6900 3100)(-6900 3050);
WIRE 16 -1 (-6475 3100)(-6900 3100);
WIRE 16 -1 (-6900 3000)(-6900 3050);
WIRE 16 -1 (-6475 3050)(-6900 3050);
WIRE 16 -1 (-6900 2950)(-6900 3000);
WIRE 16 -1 (-6475 3000)(-6900 3000);
WIRE 16 -1 (-6900 2950)(-6900 2900);
WIRE 16 -1 (-6475 2950)(-6900 2950);
WIRE 16 -1 (-6900 2850)(-6900 2900);
WIRE 16 -1 (-6475 2900)(-6900 2900);
WIRE 16 -1 (-6900 2850)(-6900 2800);
WIRE 16 -1 (-6475 2850)(-6900 2850);
WIRE 16 -1 (-6900 2800)(-6900 2750);
WIRE 16 -1 (-6475 2800)(-6900 2800);
WIRE 16 -1 (-6900 2750)(-6900 2700);
WIRE 16 -1 (-6475 2750)(-6900 2750);
WIRE 16 -1 (-6900 2600)(-6900 2700);
WIRE 16 -1 (-6475 2700)(-6900 2700);
WIRE 16 -1 (-6900 2600)(-6900 2550);
WIRE 16 -1 (-6475 2600)(-6900 2600);
WIRE 16 -1 (-6900 2550)(-6900 2500);
WIRE 16 -1 (-6475 2550)(-6900 2550);
WIRE 16 -1 (-6900 2500)(-6900 2450);
WIRE 16 -1 (-6475 2500)(-6900 2500);
WIRE 16 -1 (-6900 2450)(-6900 2400);
WIRE 16 -1 (-6475 2450)(-6900 2450);
WIRE 16 -1 (-6900 2400)(-6900 2350);
WIRE 16 -1 (-6900 2400)(-6475 2400);
WIRE 16 -1 (-6900 2350)(-6900 2300);
WIRE 16 -1 (-6475 2350)(-6900 2350);
WIRE 16 -1 (-6900 2300)(-6900 2250);
WIRE 16 -1 (-6475 2300)(-6900 2300);
WIRE 16 -1 (-6900 2250)(-6900 2200);
WIRE 16 -1 (-6475 2250)(-6900 2250);
WIRE 16 -1 (-6900 2200)(-6900 2150);
WIRE 16 -1 (-6475 2200)(-6900 2200);
WIRE 16 -1 (-6900 2150)(-6900 2100);
WIRE 16 -1 (-6475 2150)(-6900 2150);
WIRE 16 -1 (-6900 2100)(-6900 2050);
WIRE 16 -1 (-6475 2100)(-6900 2100);
WIRE 16 -1 (-6900 2050)(-6900 2000);
WIRE 16 -1 (-6475 2050)(-6900 2050);
WIRE 16 -1 (-6900 2000)(-6900 1950);
WIRE 16 -1 (-6475 2000)(-6900 2000);
WIRE 16 -1 (-6900 1950)(-6900 1900);
WIRE 16 -1 (-6475 1950)(-6900 1950);
WIRE 16 -1 (-6900 1900)(-6900 1850);
WIRE 16 -1 (-6475 1900)(-6900 1900);
WIRE 16 -1 (-6900 1850)(-6900 1800);
WIRE 16 -1 (-6475 1850)(-6900 1850);
WIRE 16 -1 (-6900 1800)(-6900 1750);
WIRE 16 -1 (-6475 1800)(-6900 1800);
WIRE 16 -1 (-6900 1750)(-6900 1700);
WIRE 16 -1 (-6475 1750)(-6900 1750);
WIRE 16 -1 (-6900 1700)(-6900 1650);
WIRE 16 -1 (-6475 1700)(-6900 1700);
WIRE 16 -1 (-6900 1650)(-6900 1600);
WIRE 16 -1 (-6475 1650)(-6900 1650);
WIRE 16 -1 (-6900 1600)(-6900 1550);
WIRE 16 -1 (-6475 1600)(-6900 1600);
WIRE 16 -1 (-6900 1550)(-6900 1500);
WIRE 16 -1 (-6475 1550)(-6900 1550);
WIRE 16 -1 (-6900 1500)(-6900 1450);
WIRE 16 -1 (-6475 1500)(-6900 1500);
WIRE 16 -1 (-6900 1450)(-6900 1400);
WIRE 16 -1 (-6475 1450)(-6900 1450);
WIRE 16 -1 (-6900 1400)(-6900 1350);
WIRE 16 -1 (-6475 1400)(-6900 1400);
WIRE 16 -1 (-6900 1350)(-6900 1300);
WIRE 16 -1 (-6475 1350)(-6900 1350);
WIRE 16 -1 (-6900 1250)(-6900 1300);
WIRE 16 -1 (-6475 1300)(-6900 1300);
WIRE 16 -1 (-6900 1200)(-6900 1250);
WIRE 16 -1 (-6475 1250)(-6900 1250);
WIRE 16 -1 (-6900 1200)(-6900 1150);
WIRE 16 -1 (-6475 1200)(-6900 1200);
WIRE 16 -1 (-6900 1100)(-6900 1150);
WIRE 16 -1 (-6475 1150)(-6900 1150);
WIRE 16 -1 (-6475 1100)(-6900 1100);
WIRE 16 -1 (-3850 4150)(-3850 4325);
WIRE 16 -1 (-3850 4100)(-3850 4150);
WIRE 16 -1 (-3850 4150)(-4275 4150);
WIRE 16 -1 (-3850 4100)(-4275 4100);
WIRE 16 -1 (-7425 2650)(-7425 2750);
WIRE 16 -1 (-6475 2650)(-7425 2650);
WIRE 16 -1 (-3400 4050)(-4275 4050);
FORCEPROP 2 LAST SIG_NAME VSENSE_PVNN_PCH_STBY_QAT
J 0
(-4072 4061);
DISPLAY 0.617021 (-4072 4061);
PAINT ORANGE (-4072 4061);
WIRE 16 -1 (-3400 3950)(-4275 3950);
FORCEPROP 2 LAST SIG_NAME VSENSE_PVNN_PCH_STBY_FPK
J 0
(-4072 3961);
DISPLAY 0.617021 (-4072 3961);
PAINT ORANGE (-4072 3961);
DOT 1 (-2800 925);
DOT 1 (-6900 1150);
DOT 1 (-6900 1200);
DOT 1 (-6900 1250);
DOT 1 (-6900 1350);
DOT 1 (-6900 1300);
DOT 1 (-6900 1400);
DOT 1 (-6900 1450);
DOT 1 (-6900 1500);
DOT 1 (-6900 1550);
DOT 1 (-6900 1600);
DOT 1 (-6900 1650);
DOT 1 (-6900 1700);
DOT 1 (-6900 1750);
DOT 1 (-6900 1800);
DOT 1 (-6900 1850);
DOT 1 (-6900 1900);
DOT 1 (-6900 1950);
DOT 1 (-6900 2000);
DOT 1 (-6900 2050);
DOT 1 (-6900 2100);
DOT 1 (-6900 2150);
DOT 1 (-6900 2200);
DOT 1 (-6900 2250);
DOT 1 (-6900 2300);
DOT 1 (-6900 2350);
DOT 1 (-6900 2400);
DOT 1 (-6900 2450);
DOT 1 (-6900 2500);
DOT 1 (-6900 2600);
DOT 1 (-6900 2550);
DOT 1 (-6900 2700);
DOT 1 (-6900 2750);
DOT 1 (-6900 2800);
DOT 1 (-6900 2850);
DOT 1 (-6900 2900);
DOT 1 (-6900 2950);
DOT 1 (-6900 3000);
DOT 1 (-6900 3050);
DOT 1 (-6900 3100);
DOT 1 (-6900 3150);
DOT 1 (-6900 3200);
DOT 1 (-6900 3250);
DOT 1 (-6900 3300);
DOT 1 (-6900 3350);
DOT 1 (-6900 3400);
DOT 1 (-6900 3450);
DOT 1 (-6900 3500);
DOT 1 (-6900 3550);
DOT 1 (-6900 3600);
DOT 1 (-6900 3650);
DOT 1 (-6900 3700);
DOT 1 (-6900 3750);
DOT 1 (-6900 3800);
DOT 1 (-6900 3900);
DOT 1 (-6900 3850);
DOT 1 (-6900 3950);
DOT 1 (-6900 4000);
DOT 1 (-6900 4050);
DOT 1 (-6900 4100);
DOT 1 (-6900 4150);
DOT 1 (-3850 4150);
DOT 1 (-2800 825);
DOT 1 (-2800 875);
DOT 1 (-2800 975);
DOT 1 (-2800 1025);
DOT 1 (-2800 1075);
DOT 1 (-2800 1125);
DOT 1 (-2800 1175);
DOT 1 (-2800 1225);
DOT 1 (-2800 1275);
DOT 1 (-2800 1325);
DOT 1 (-2800 1375);
DOT 1 (-2800 1425);
DOT 1 (-2800 1475);
DOT 1 (-2800 1525);
DOT 1 (-2800 1575);
DOT 1 (-2800 1625);
DOT 1 (-2800 1725);
DOT 1 (-2800 1675);
DOT 1 (-2800 1775);
DOT 1 (-2800 1825);
DOT 1 (-2800 1875);
DOT 1 (-2800 1925);
DOT 1 (-2800 1975);
DOT 1 (-2800 2025);
DOT 1 (-2800 2075);
DOT 1 (-2800 2125);
DOT 1 (-2800 2175);
DOT 1 (-2800 2225);
DOT 1 (-2800 2275);
DOT 1 (-2800 2375);
DOT 1 (-2800 2325);
DOT 1 (-2800 2425);
DOT 1 (-2800 2475);
DOT 1 (-2800 2525);
DOT 1 (-2800 2625);
DOT 1 (-2800 2575);
DOT 1 (-2800 2675);
DOT 1 (-2800 2725);
DOT 1 (-2800 2775);
DOT 1 (-2800 2875);
DOT 1 (-2800 2825);
DOT 1 (-2800 2925);
DOT 1 (-2800 2975);
DOT 1 (-2800 3025);
DOT 1 (-2800 3075);
DOT 1 (-2800 3125);
DOT 1 (-2800 3175);
DOT 1 (-2800 3275);
DOT 1 (-2800 3225);
DOT 1 (-2800 3325);
DOT 1 (-2800 3375);
DOT 1 (-2800 3425);
DOT 1 (-2800 3525);
DOT 1 (-2800 3475);
DOT 1 (-2800 3575);
DOT 1 (-2800 3625);
DOT 1 (-2800 3675);
DOT 1 (-2800 3775);
DOT 1 (-2800 3725);
DOT 1 (-2800 3825);
DOT 1 (-2800 3875);
DOT 1 (-2800 3925);
DOT 1 (-2800 3975);
DOT 1 (-2800 4025);
DOT 1 (-375 825);
DOT 1 (-375 875);
DOT 1 (-375 925);
DOT 1 (-375 975);
DOT 1 (-375 1025);
DOT 1 (-375 1075);
DOT 1 (-375 1125);
DOT 1 (-375 1225);
DOT 1 (-375 1175);
DOT 1 (-375 1275);
DOT 1 (-375 1325);
DOT 1 (-375 1375);
DOT 1 (-375 1475);
DOT 1 (-375 1425);
DOT 1 (-375 1525);
DOT 1 (-375 1575);
DOT 1 (-375 1625);
DOT 1 (-375 1725);
DOT 1 (-375 1675);
DOT 1 (-375 1775);
DOT 1 (-375 1825);
DOT 1 (-375 1875);
DOT 1 (-375 1925);
DOT 1 (-375 1975);
DOT 1 (-375 2025);
DOT 1 (-375 2075);
DOT 1 (-375 2125);
DOT 1 (-375 2175);
DOT 1 (-375 2225);
DOT 1 (-375 2275);
DOT 1 (-375 2375);
DOT 1 (-375 2325);
DOT 1 (-375 2425);
DOT 1 (-375 2475);
DOT 1 (-375 2525);
DOT 1 (-375 2575);
DOT 1 (-375 2625);
DOT 1 (-375 2675);
DOT 1 (-375 2725);
DOT 1 (-375 2775);
DOT 1 (-375 2825);
DOT 1 (-375 2875);
DOT 1 (-375 2925);
DOT 1 (-375 2975);
DOT 1 (-375 3025);
DOT 1 (-375 3075);
DOT 1 (-375 3175);
DOT 1 (-375 3125);
DOT 1 (-375 3225);
DOT 1 (-375 3275);
DOT 1 (-375 3325);
DOT 1 (-375 3375);
DOT 1 (-375 3425);
DOT 1 (-375 3525);
DOT 1 (-375 3475);
DOT 1 (-375 3575);
DOT 1 (-375 3625);
DOT 1 (-375 3675);
DOT 1 (-375 3725);
DOT 1 (-375 3775);
DOT 1 (-375 3825);
DOT 1 (-375 3875);
DOT 1 (-375 3925);
DOT 1 (-375 4025);
DOT 1 (-375 3975);
DOT 1 (-2800 4075);
DOT 1 (-375 4075);
DOT 1 (-2800 4125);
DOT 1 (-2800 4175);
DOT 1 (-2800 4225);
DOT 1 (-375 4125);
DOT 1 (-375 4175);
DOT 1 (-375 4225);
FORCENOTE
ROOM=SB
(-7850 225) 0;
DISPLAY LEFT (-7850 225);
DISPLAY 1.021277 (-7850 225);
PAINT PURPLE (-7850 225);
QUIT
